#ISCELL
  mstr_misc dns *
  *
#ISCELL
  mstr_symbols design_note *
  *
#ISCELL
  mstr_symbols intel_corp_bpage *
  *
#ISCELL
  mstr_symbols p3v3_stby *
  page235_i135
#ISCELL
  mstr_standard offpage *
  page235_i136
#ISCELL
  mstr_standard offpage *
  page235_i139
#ISCELL
  mstr_standard offpage *
  page235_i142
#CELL
  dev_discrete cap_a *
  page235_i143
#ISCELL
  mstr_symbols gnd *
  page235_i144
#CELL
  dev_discrete cap_a *
  page235_i145
#ISCELL
  mstr_symbols gnd *
  page235_i146
#CELL
  mstr_discrete res *
  page235_i147
#CELL
  mstr_discrete res *
  page235_i148
#CELL
  mstr_discrete res *
  page235_i149
#CELL
  dev_discrete cap_a *
  page235_i151
#ISCELL
  mstr_symbols gnd *
  page235_i152
#CELL
  mstr_discrete cap *
  page235_i153
#CELL
  mstr_discrete res *
  page235_i154
#ISCELL
  mstr_symbols gnd *
  page235_i155
#ISCELL
  mstr_standard offpage *
  page235_i156
#ISCELL
  mstr_standard offpage *
  page235_i157
#ISCELL
  mstr_symbols p3v3_stby *
  page235_i158
#CELL
  mstr_discrete res *
  page235_i159
#CELL
  mstr_discrete res *
  page235_i165
#CELL
  mstr_discrete res *
  page235_i166
#ISCELL
  mstr_standard offpage *
  page235_i168
#CELL
  dev_discrete cap_a *
  page235_i169
#ISCELL
  mstr_symbols gnd *
  page235_i170
#ISCELL
  mstr_symbols gnd *
  page235_i178
#ISCELL
  mstr_symbols gnd *
  page235_i181
#ISCELL
  mstr_symbols gnd *
  page235_i183
#ISCELL
  mstr_standard offpage *
  page235_i185
#ISCELL
  mstr_standard offpage *
  page235_i186
#ISCELL
  mstr_standard offpage *
  page235_i187
#ISCELL
  mstr_standard offpage *
  page235_i188
#ISCELL
  mstr_standard offpage *
  page235_i189
#ISCELL
  mstr_standard offpage *
  page235_i191
#ISCELL
  mstr_standard offpage *
  page235_i194
#ISCELL
  mstr_standard offpage *
  page235_i195
#ISCELL
  mstr_standard offpage *
  page235_i198
#ISCELL
  mstr_standard offpage *
  page235_i199
#ISCELL
  mstr_standard offpage *
  page235_i200
#CELL
  mstr_discrete cap *
  page235_i209
#CELL
  mstr_discrete res *
  page235_i210
#ISCELL
  mstr_standard offpage *
  page235_i211
#ISCELL
  mstr_standard offpage *
  page235_i212
#ISCELL
  mstr_standard offpage *
  page235_i215
#CELL
  mstr_discrete res *
  page235_i216
#CELL
  mstr_discrete res *
  page235_i217
#CELL
  mstr_discrete cap *
  page235_i218
#ISCELL
  mstr_symbols gnd *
  page235_i219
#CELL
  mstr_discrete res *
  page235_i221
#CELL
  mstr_discrete res *
  page235_i222
#ISCELL
  mstr_symbols vcc_core *
  page235_i228
#CELL
  mstr_controller pxe1110b *
  page235_i229
#ISCELL
  mstr_standard offpage *
  page235_i232
#ISCELL
  mstr_standard offpage *
  page235_i234
#CELL
  w_hdl sc22p50v2jn-4gp *
  page235_i239
#CELL
  w_hdl sc22p50v2jn-4gp *
  page235_i240
#CELL
  mstr_discrete res *
  page235_i241
#CELL
  mstr_discrete res *
  page235_i242
#ISCELL
  mstr_symbols gnd *
  page235_i243
#CELL
  mstr_discrete cap *
  page235_i244
#ISCELL
  mstr_symbols gnd *
  page235_i245
#CELL
  mstr_discrete cap *
  page235_i246
#CELL
  mstr_discrete res *
  page235_i247
#CELL
  mstr_discrete res *
  page235_i248
#CELL
  mstr_discrete res *
  page235_i249
#CELL
  mstr_discrete res *
  page235_i252
#CELL
  mstr_discrete res *
  page235_i253
#CELL
  mstr_discrete res *
  page235_i254
#CELL
  dev_discrete cap_a *
  page235_i255
